(kicad_pcb
	(version 20221018)
	(generator pcbnew)
	(general
    (thickness 1.6)
  )
	(paper "A4")
	(title_block
    (title "NUC Computer Cluster Power Breakout HW")
    (date "2023-10-18")
    (rev "1.4.3")
    (company "Antmicro Ltd.")
		(comment 9 "footprints 30-34 of 234")
	)
	(layers
    (0 "F.Cu" mixed)
    (1 "In1.Cu" power)
    (2 "In2.Cu" mixed)
    (31 "B.Cu" power)
    (32 "B.Adhes" user "B.Adhesive")
    (33 "F.Adhes" user "F.Adhesive")
    (34 "B.Paste" user)
    (35 "F.Paste" user)
    (36 "B.SilkS" user "B.Silkscreen")
    (37 "F.SilkS" user "F.Silkscreen")
    (38 "B.Mask" user)
    (39 "F.Mask" user)
    (40 "Dwgs.User" user "User.Drawings")
    (41 "Cmts.User" user "User.Comments")
    (42 "Eco1.User" user "User.Eco1")
    (43 "Eco2.User" user "User.Eco2")
    (44 "Edge.Cuts" user)
    (45 "Margin" user)
    (46 "B.CrtYd" user "B.Courtyard")
    (47 "F.CrtYd" user "F.Courtyard")
    (48 "B.Fab" user)
    (49 "F.Fab" user)
  )
	(footprint "antmicro-footprints:MOLEX_39288080" (layer "F.Cu")
    (at 128.25 74.7 90)
    (property "Author" "Antmicro")
    (property "License" "Apache-2.0")
    (property "MPN" "39-28-8080")
    (property "Manufacturer" "Molex")
    (property "Sheetfile" "d1600e-psu-breakout-board.kicad_sch")
    (property "Sheetname" "")
    (property "ki_description" "Pin Header, THT, Vertical, UL94V-2, Power, Wire-to-Board, 4.2 mm, 2 Rows, 8 Contacts, Mini-fit Jr, 5566 series")
    (property "ki_keywords" "VERTICAL, THT, HEADER, CONNECTOR, MALE, WIRE-BOARD, POWER")
    (attr through_hole)
    (fp_text reference "J7" (at -1.9 -2.8 90) (layer "F.SilkS")
        (effects (font (size 0.7 0.7) (thickness 0.15)) (justify left bottom))
    )
    (fp_text value "Molex_Mini-Fit-Jr_2x4_39-28-8080" (at 4.49 11.365 90) (layer "F.Fab")
        (effects (font (size 0.7 0.7) (thickness 0.15)) (justify left bottom))
    )
    (fp_text user "PTH D1.40 +/- 0.05" (at -3.5 13.365 90) (layer "F.Fab") hide
        (effects (font (size 0.7 0.7) (thickness 0.15)) (justify left bottom))
    )
    (fp_text user "${REFERENCE}" (at -3.5 15.765 90) (layer "F.Fab") hide
        (effects (font (size 0.7 0.7) (thickness 0.15)) (justify left bottom))
    )
    (fp_text user "License: Apache-2.0" (at -3.5 14.565 90) (layer "F.Fab") hide
        (effects (font (size 0.7 0.7) (thickness 0.15)) (justify left bottom))
    )
    (fp_text user "Author: Antmicro" (at -3.5 16.965 90) (layer "F.Fab") hide
        (effects (font (size 0.7 0.7) (thickness 0.15)) (justify left bottom))
    )
    (fp_line (start -3.1 8.75) (end -3.1 -0.98)
      (stroke (width 0.15) (type solid)) (layer "F.SilkS"))
    (fp_line (start -1.83 -2.25) (end -3.1 -0.98)
      (stroke (width 0.15) (type solid)) (layer "F.SilkS"))
    (fp_line (start -1.83 -2.25) (end 15.7 -2.25)
      (stroke (width 0.15) (type solid)) (layer "F.SilkS"))
    (fp_line (start -0.4 -3.327) (end 0 -2.627)
      (stroke (width 0.15) (type solid)) (layer "F.SilkS"))
    (fp_line (start 0 -2.627) (end 0.4 -3.327)
      (stroke (width 0.15) (type solid)) (layer "F.SilkS"))
    (fp_line (start 0.4 -3.327) (end -0.4 -3.327)
      (stroke (width 0.15) (type solid)) (layer "F.SilkS"))
    (fp_line (start 15.7 -2.25) (end 15.7 8.75)
      (stroke (width 0.15) (type solid)) (layer "F.SilkS"))
    (fp_line (start 15.7 8.75) (end -3.1 8.75)
      (stroke (width 0.15) (type solid)) (layer "F.SilkS"))
    (fp_circle (center 0 -3) (end 0.05 -3)
      (stroke (width 0.15) (type solid)) (fill solid) (layer "F.SilkS"))
    (fp_circle (center 0 5.5) (end 0.513 5.5)
      (stroke (width 1.0262) (type solid)) (fill none) (layer "B.Mask"))
    (fp_circle (center 4.2 0) (end 4.713 0)
      (stroke (width 1.0262) (type solid)) (fill none) (layer "B.Mask"))
    (fp_circle (center 4.2 5.5) (end 4.713 5.5)
      (stroke (width 1.0262) (type solid)) (fill none) (layer "B.Mask"))
    (fp_circle (center 8.4 0) (end 8.913 0)
      (stroke (width 1.0262) (type solid)) (fill none) (layer "B.Mask"))
    (fp_circle (center 8.4 5.5) (end 8.913 5.5)
      (stroke (width 1.0262) (type solid)) (fill none) (layer "B.Mask"))
    (fp_circle (center 12.6 0) (end 13.113 0)
      (stroke (width 1.0262) (type solid)) (fill none) (layer "B.Mask"))
    (fp_circle (center 12.6 5.5) (end 13.113 5.5)
      (stroke (width 1.0262) (type solid)) (fill none) (layer "B.Mask"))
    (fp_poly
      (pts
        (xy -1.026 -1.026)
        (xy 1.026 -1.026)
        (xy 1.026 1.026)
        (xy -1.026 1.026)
      )

      (stroke (width 0.01) (type solid)) (fill solid) (layer "B.Mask"))
    (fp_circle (center 0 5.5) (end 0.513 5.5)
      (stroke (width 1.0262) (type solid)) (fill none) (layer "F.Mask"))
    (fp_circle (center 4.2 0) (end 4.713 0)
      (stroke (width 1.0262) (type solid)) (fill none) (layer "F.Mask"))
    (fp_circle (center 4.2 5.5) (end 4.713 5.5)
      (stroke (width 1.0262) (type solid)) (fill none) (layer "F.Mask"))
    (fp_circle (center 8.4 0) (end 8.913 0)
      (stroke (width 1.0262) (type solid)) (fill none) (layer "F.Mask"))
    (fp_circle (center 8.4 5.5) (end 8.913 5.5)
      (stroke (width 1.0262) (type solid)) (fill none) (layer "F.Mask"))
    (fp_circle (center 12.6 0) (end 13.113 0)
      (stroke (width 1.0262) (type solid)) (fill none) (layer "F.Mask"))
    (fp_circle (center 12.6 5.5) (end 13.113 5.5)
      (stroke (width 1.0262) (type solid)) (fill none) (layer "F.Mask"))
    (fp_poly
      (pts
        (xy -1.026 -1.026)
        (xy 1.026 -1.026)
        (xy 1.026 1.026)
        (xy -1.026 1.026)
      )

      (stroke (width 0.01) (type solid)) (fill solid) (layer "F.Mask"))
    (fp_rect (start -3.5 -2.7) (end 16.1 9.1)
      (stroke (width 0.05) (type solid)) (fill none) (layer "F.CrtYd"))
    (fp_line (start -3.1 8.75) (end -3.1 -0.98)
      (stroke (width 0.15) (type solid)) (layer "F.Fab"))
    (fp_line (start -1.83 -2.25) (end -3.1 -0.98)
      (stroke (width 0.15) (type solid)) (layer "F.Fab"))
    (fp_line (start -1.83 -2.25) (end 15.7 -2.25)
      (stroke (width 0.15) (type solid)) (layer "F.Fab"))
    (fp_line (start -0.4 -3.327) (end 0 -2.627)
      (stroke (width 0.15) (type solid)) (layer "F.Fab"))
    (fp_line (start 0 -2.627) (end 0.4 -3.327)
      (stroke (width 0.15) (type solid)) (layer "F.Fab"))
    (fp_line (start 0.4 -3.327) (end -0.4 -3.327)
      (stroke (width 0.15) (type solid)) (layer "F.Fab"))
    (fp_line (start 15.7 -2.25) (end 15.7 8.75)
      (stroke (width 0.15) (type solid)) (layer "F.Fab"))
    (fp_line (start 15.7 8.75) (end -3.1 8.75)
      (stroke (width 0.15) (type solid)) (layer "F.Fab"))
    (pad "1" thru_hole rect (at 0 0 90) (size 1.9 1.9) (drill 1.4) (layers "*.Cu")
      (net 4 "GND") (pinfunction "1") (pintype "bidirectional"))
    (pad "2" thru_hole circle (at 4.2 0 90) (size 1.9 1.9) (drill 1.4) (layers "*.Cu")
      (net 4 "GND") (pinfunction "2") (pintype "bidirectional"))
    (pad "3" thru_hole circle (at 8.4 0 90) (size 1.9 1.9) (drill 1.4) (layers "*.Cu")
      (net 4 "GND") (pinfunction "3") (pintype "bidirectional"))
    (pad "4" thru_hole circle (at 12.6 0 90) (size 1.9 1.9) (drill 1.4) (layers "*.Cu")
      (net 4 "GND") (pinfunction "4") (pintype "bidirectional"))
    (pad "5" thru_hole circle (at 0 5.5 90) (size 1.9 1.9) (drill 1.4) (layers "*.Cu")
      (net 44 "LOAD_2") (pinfunction "5") (pintype "bidirectional"))
    (pad "6" thru_hole circle (at 4.2 5.5 90) (size 1.9 1.9) (drill 1.4) (layers "*.Cu")
      (net 44 "LOAD_2") (pinfunction "6") (pintype "bidirectional"))
    (pad "7" thru_hole circle (at 8.4 5.5 90) (size 1.9 1.9) (drill 1.4) (layers "*.Cu")
      (net 44 "LOAD_2") (pinfunction "7") (pintype "bidirectional"))
    (pad "8" thru_hole circle (at 12.6 5.5 90) (size 1.9 1.9) (drill 1.4) (layers "*.Cu")
      (net 44 "LOAD_2") (pinfunction "8") (pintype "bidirectional"))
  )
	(footprint "antmicro-footprints:TP_SMD_1mm" (layer "F.Cu")
    (at 175.95 96.3008)
    (property "Author" "Antmicro")
    (property "License" "Apache-2.0")
    (property "MPN" "")
    (property "Manufacturer" "")
    (property "Sheetfile" "ftdi-module.kicad_sch")
    (property "Sheetname" "FTDI")
    (property "exclude_from_bom" "")
    (property "ki_description" "Test point 1mm SMD")
    (property "ki_keywords" "TESTPOINT")
    (attr exclude_from_pos_files exclude_from_bom)
    (fp_text reference "SDA1" (at -1.85 -0.0008) (layer "F.SilkS")
        (effects (font (size 0.7 0.7) (thickness 0.15)))
    )
    (fp_text value "TP_1mm_SMD" (at 0 -0.5) (layer "F.Fab") hide
        (effects (font (size 1 1) (thickness 0.15)))
    )
    (fp_text user "License: Apache-2.0" (at -0.5 5.2) (layer "F.Fab") hide
        (effects (font (size 0.7 0.7) (thickness 0.15)) (justify left bottom))
    )
    (fp_text user "${REFERENCE}" (at -0.5 2.8) (layer "F.Fab") hide
        (effects (font (size 0.7 0.7) (thickness 0.15)) (justify left bottom))
    )
    (fp_text user "Author: Antmicro" (at -0.5 4) (layer "F.Fab") hide
        (effects (font (size 0.7 0.7) (thickness 0.15)) (justify left bottom))
    )
    (fp_circle (center 0 0) (end 0.6 0)
      (stroke (width 0.05) (type default)) (fill none) (layer "F.CrtYd"))
    (pad "1" smd circle (at 0 0) (size 1 1) (layers "F.Cu" "F.Mask")
      (net 18 "SDA") (pinfunction "1") (pintype "passive"))
  )
	(footprint "antmicro-footprints:MOLEX_39288080" (layer "F.Cu")
    (at 162.25 74.7 90)
    (property "Author" "Antmicro")
    (property "License" "Apache-2.0")
    (property "MPN" "39-28-8080")
    (property "Manufacturer" "Molex")
    (property "Sheetfile" "d1600e-psu-breakout-board.kicad_sch")
    (property "Sheetname" "")
    (property "ki_description" "Pin Header, THT, Vertical, UL94V-2, Power, Wire-to-Board, 4.2 mm, 2 Rows, 8 Contacts, Mini-fit Jr, 5566 series")
    (property "ki_keywords" "VERTICAL, THT, HEADER, CONNECTOR, MALE, WIRE-BOARD, POWER")
    (attr through_hole)
    (fp_text reference "J8" (at -2.15 -2.65 90) (layer "F.SilkS")
        (effects (font (size 0.7 0.7) (thickness 0.15)) (justify left bottom))
    )
    (fp_text value "Molex_Mini-Fit-Jr_2x4_39-28-8080" (at 4.49 11.365 90) (layer "F.Fab")
        (effects (font (size 0.7 0.7) (thickness 0.15)) (justify left bottom))
    )
    (fp_text user "License: Apache-2.0" (at -3.5 14.565 90) (layer "F.Fab") hide
        (effects (font (size 0.7 0.7) (thickness 0.15)) (justify left bottom))
    )
    (fp_text user "${REFERENCE}" (at -3.5 15.765 90) (layer "F.Fab") hide
        (effects (font (size 0.7 0.7) (thickness 0.15)) (justify left bottom))
    )
    (fp_text user "Author: Antmicro" (at -3.5 16.965 90) (layer "F.Fab") hide
        (effects (font (size 0.7 0.7) (thickness 0.15)) (justify left bottom))
    )
    (fp_text user "PTH D1.40 +/- 0.05" (at -3.5 13.365 90) (layer "F.Fab") hide
        (effects (font (size 0.7 0.7) (thickness 0.15)) (justify left bottom))
    )
    (fp_line (start -3.1 8.75) (end -3.1 -0.98)
      (stroke (width 0.15) (type solid)) (layer "F.SilkS"))
    (fp_line (start -1.83 -2.25) (end -3.1 -0.98)
      (stroke (width 0.15) (type solid)) (layer "F.SilkS"))
    (fp_line (start -1.83 -2.25) (end 15.7 -2.25)
      (stroke (width 0.15) (type solid)) (layer "F.SilkS"))
    (fp_line (start -0.4 -3.327) (end 0 -2.627)
      (stroke (width 0.15) (type solid)) (layer "F.SilkS"))
    (fp_line (start 0 -2.627) (end 0.4 -3.327)
      (stroke (width 0.15) (type solid)) (layer "F.SilkS"))
    (fp_line (start 0.4 -3.327) (end -0.4 -3.327)
      (stroke (width 0.15) (type solid)) (layer "F.SilkS"))
    (fp_line (start 15.7 -2.25) (end 15.7 8.75)
      (stroke (width 0.15) (type solid)) (layer "F.SilkS"))
    (fp_line (start 15.7 8.75) (end -3.1 8.75)
      (stroke (width 0.15) (type solid)) (layer "F.SilkS"))
    (fp_circle (center 0 -3) (end 0.05 -3)
      (stroke (width 0.15) (type solid)) (fill solid) (layer "F.SilkS"))
    (fp_circle (center 0 5.5) (end 0.513 5.5)
      (stroke (width 1.0262) (type solid)) (fill none) (layer "B.Mask"))
    (fp_circle (center 4.2 0) (end 4.713 0)
      (stroke (width 1.0262) (type solid)) (fill none) (layer "B.Mask"))
    (fp_circle (center 4.2 5.5) (end 4.713 5.5)
      (stroke (width 1.0262) (type solid)) (fill none) (layer "B.Mask"))
    (fp_circle (center 8.4 0) (end 8.913 0)
      (stroke (width 1.0262) (type solid)) (fill none) (layer "B.Mask"))
    (fp_circle (center 8.4 5.5) (end 8.913 5.5)
      (stroke (width 1.0262) (type solid)) (fill none) (layer "B.Mask"))
    (fp_circle (center 12.6 0) (end 13.113 0)
      (stroke (width 1.0262) (type solid)) (fill none) (layer "B.Mask"))
    (fp_circle (center 12.6 5.5) (end 13.113 5.5)
      (stroke (width 1.0262) (type solid)) (fill none) (layer "B.Mask"))
    (fp_poly
      (pts
        (xy -1.026 -1.026)
        (xy 1.026 -1.026)
        (xy 1.026 1.026)
        (xy -1.026 1.026)
      )

      (stroke (width 0.01) (type solid)) (fill solid) (layer "B.Mask"))
    (fp_circle (center 0 5.5) (end 0.513 5.5)
      (stroke (width 1.0262) (type solid)) (fill none) (layer "F.Mask"))
    (fp_circle (center 4.2 0) (end 4.713 0)
      (stroke (width 1.0262) (type solid)) (fill none) (layer "F.Mask"))
    (fp_circle (center 4.2 5.5) (end 4.713 5.5)
      (stroke (width 1.0262) (type solid)) (fill none) (layer "F.Mask"))
    (fp_circle (center 8.4 0) (end 8.913 0)
      (stroke (width 1.0262) (type solid)) (fill none) (layer "F.Mask"))
    (fp_circle (center 8.4 5.5) (end 8.913 5.5)
      (stroke (width 1.0262) (type solid)) (fill none) (layer "F.Mask"))
    (fp_circle (center 12.6 0) (end 13.113 0)
      (stroke (width 1.0262) (type solid)) (fill none) (layer "F.Mask"))
    (fp_circle (center 12.6 5.5) (end 13.113 5.5)
      (stroke (width 1.0262) (type solid)) (fill none) (layer "F.Mask"))
    (fp_poly
      (pts
        (xy -1.026 -1.026)
        (xy 1.026 -1.026)
        (xy 1.026 1.026)
        (xy -1.026 1.026)
      )

      (stroke (width 0.01) (type solid)) (fill solid) (layer "F.Mask"))
    (fp_rect (start -3.5 -2.7) (end 16.1 9.1)
      (stroke (width 0.05) (type solid)) (fill none) (layer "F.CrtYd"))
    (fp_line (start -3.1 8.75) (end -3.1 -0.98)
      (stroke (width 0.15) (type solid)) (layer "F.Fab"))
    (fp_line (start -1.83 -2.25) (end -3.1 -0.98)
      (stroke (width 0.15) (type solid)) (layer "F.Fab"))
    (fp_line (start -1.83 -2.25) (end 15.7 -2.25)
      (stroke (width 0.15) (type solid)) (layer "F.Fab"))
    (fp_line (start -0.4 -3.327) (end 0 -2.627)
      (stroke (width 0.15) (type solid)) (layer "F.Fab"))
    (fp_line (start 0 -2.627) (end 0.4 -3.327)
      (stroke (width 0.15) (type solid)) (layer "F.Fab"))
    (fp_line (start 0.4 -3.327) (end -0.4 -3.327)
      (stroke (width 0.15) (type solid)) (layer "F.Fab"))
    (fp_line (start 15.7 -2.25) (end 15.7 8.75)
      (stroke (width 0.15) (type solid)) (layer "F.Fab"))
    (fp_line (start 15.7 8.75) (end -3.1 8.75)
      (stroke (width 0.15) (type solid)) (layer "F.Fab"))
    (pad "1" thru_hole rect (at 0 0 90) (size 1.9 1.9) (drill 1.4) (layers "*.Cu")
      (net 4 "GND") (pinfunction "1") (pintype "bidirectional"))
    (pad "2" thru_hole circle (at 4.2 0 90) (size 1.9 1.9) (drill 1.4) (layers "*.Cu")
      (net 4 "GND") (pinfunction "2") (pintype "bidirectional"))
    (pad "3" thru_hole circle (at 8.4 0 90) (size 1.9 1.9) (drill 1.4) (layers "*.Cu")
      (net 4 "GND") (pinfunction "3") (pintype "bidirectional"))
    (pad "4" thru_hole circle (at 12.6 0 90) (size 1.9 1.9) (drill 1.4) (layers "*.Cu")
      (net 4 "GND") (pinfunction "4") (pintype "bidirectional"))
    (pad "5" thru_hole circle (at 0 5.5 90) (size 1.9 1.9) (drill 1.4) (layers "*.Cu")
      (net 45 "LOAD_4") (pinfunction "5") (pintype "bidirectional"))
    (pad "6" thru_hole circle (at 4.2 5.5 90) (size 1.9 1.9) (drill 1.4) (layers "*.Cu")
      (net 45 "LOAD_4") (pinfunction "6") (pintype "bidirectional"))
    (pad "7" thru_hole circle (at 8.4 5.5 90) (size 1.9 1.9) (drill 1.4) (layers "*.Cu")
      (net 45 "LOAD_4") (pinfunction "7") (pintype "bidirectional"))
    (pad "8" thru_hole circle (at 12.6 5.5 90) (size 1.9 1.9) (drill 1.4) (layers "*.Cu")
      (net 45 "LOAD_4") (pinfunction "8") (pintype "bidirectional"))
  )
	(footprint "antmicro-footprints:R_0402_1005Metric" (layer "F.Cu")
    (at 180.1 92.1 180)
    (descr "Resistor SMD 0402")
    (tags "resistor SMD 0402")
    (property "Author" "Antmicro")
    (property "License" "Apache-2.0")
    (property "MPN" "CR0402-FX-4701GLF")
    (property "Manufacturer" "Bourns")
    (property "Sheetfile" "power-switch.kicad_sch")
    (property "Sheetname" "Power switch 5")
    (property "Tolerance" "1%")
    (property "Val" "4k7")
    (property "ki_description" "SMD Chip Resistor, 4.7 kohm, ± 1%, 62.5 mW, 0402 [1005 Metric], Thick Film, General Purpose")
    (property "ki_keywords" "0402, SMT, RESISTOR, PASSIVE")
    (zone_connect 1)
    (attr smd)
    (fp_text reference "R25" (at 2.25 -1.95 180) (layer "F.SilkS")
        (effects (font (size 0.7 0.7) (thickness 0.15)))
    )
    (fp_text value "R_4k7_0402" (at 0 1.17) (layer "F.Fab") hide
        (effects (font (size 1 1) (thickness 0.15)))
    )
    (fp_text user "${REFERENCE}" (at 0 0) (layer "F.Fab")
        (effects (font (size 0.7 0.7) (thickness 0.15)))
    )
    (fp_text user "License: Apache-2.0" (at -0.95 5.169 180) (layer "F.Fab") hide
        (effects (font (size 0.7 0.7) (thickness 0.15)) (justify left bottom))
    )
    (fp_text user "Author: Antmicro" (at -0.95 4.169 180) (layer "F.Fab") hide
        (effects (font (size 0.7 0.7) (thickness 0.15)) (justify left bottom))
    )
    (fp_rect (start -0.925 -0.47) (end 0.925 0.47)
      (stroke (width 0.05) (type default)) (fill none) (layer "F.CrtYd"))
    (fp_rect (start -0.5 -0.25) (end 0.5 0.25)
      (stroke (width 0.15) (type solid)) (fill none) (layer "F.Fab"))
    (pad "1" smd roundrect (at -0.48 0 180) (size 0.59 0.64) (layers "F.Cu" "F.Paste" "F.Mask") (roundrect_rratio 0.25)
      (net 11 "VCC12V0") (pintype "passive"))
    (pad "2" smd roundrect (at 0.48 0 180) (size 0.59 0.64) (layers "F.Cu" "F.Paste" "F.Mask") (roundrect_rratio 0.25)
      (net 87 "Net-(D19-A)") (pintype "passive"))
  )
	(footprint "antmicro-footprints:R_0402_1005Metric" (layer "F.Cu")
    (at 114.1 91.85 180)
    (descr "Resistor SMD 0402")
    (tags "resistor SMD 0402")
    (property "Author" "Antmicro")
    (property "License" "Apache-2.0")
    (property "MPN" "CR0402-FX-4701GLF")
    (property "Manufacturer" "Bourns")
    (property "Sheetfile" "power-switch.kicad_sch")
    (property "Sheetname" "Power switch 1")
    (property "Tolerance" "1%")
    (property "Val" "4k7")
    (property "ki_description" "SMD Chip Resistor, 4.7 kohm, ± 1%, 62.5 mW, 0402 [1005 Metric], Thick Film, General Purpose")
    (property "ki_keywords" "0402, SMT, RESISTOR, PASSIVE")
    (zone_connect 1)
    (attr smd)
    (fp_text reference "R22" (at 1.15 -1.3 180) (layer "F.SilkS")
        (effects (font (size 0.7 0.7) (thickness 0.15)) (justify left bottom))
    )
    (fp_text value "R_4k7_0402" (at -1.011843 1.772047 180) (layer "F.Fab")
        (effects (font (size 0.7 0.7) (thickness 0.15)) (justify left bottom))
    )
    (fp_text user "License: Apache-2.0" (at -0.95 5.169 180) (layer "F.Fab") hide
        (effects (font (size 0.7 0.7) (thickness 0.15)) (justify left bottom))
    )
    (fp_text user "Author: Antmicro" (at -0.95 4.169 180) (layer "F.Fab") hide
        (effects (font (size 0.7 0.7) (thickness 0.15)) (justify left bottom))
    )
    (fp_text user "${REFERENCE}" (at -0.95 3.168 180) (layer "F.Fab") hide
        (effects (font (size 0.7 0.7) (thickness 0.15)) (justify left bottom))
    )
    (fp_rect (start -0.925 -0.47) (end 0.925 0.47)
      (stroke (width 0.05) (type default)) (fill none) (layer "F.CrtYd"))
    (fp_rect (start -0.5 -0.25) (end 0.5 0.25)
      (stroke (width 0.15) (type solid)) (fill none) (layer "F.Fab"))
    (pad "1" smd roundrect (at -0.48 0 180) (size 0.59 0.64) (layers "F.Cu" "F.Paste" "F.Mask") (roundrect_rratio 0.25)
      (net 11 "VCC12V0") (pintype "passive"))
    (pad "2" smd roundrect (at 0.48 0 180) (size 0.59 0.64) (layers "F.Cu" "F.Paste" "F.Mask") (roundrect_rratio 0.25)
      (net 83 "Net-(D15-A)") (pintype "passive"))
  )
)
